(kicad_pcb
	(version 20260206)
	(generator "pcbnew")
	(generator_version "10.0")
	(general
		(thickness 1.6)
		(legacy_teardrops no)
	)
	(paper "A4")
	(title_block
		(title "Bryce Canyon_SCC_16316-1_OCP.brd")
		(comment 1 "Bryce Canyon / footprints 377-383 of 1561")
	)
	(layers
		(0 "F.Cu" signal "TOP")
		(4 "In1.Cu" signal "L2GND")
		(6 "In2.Cu" signal "L3")
		(8 "In3.Cu" signal "L4VCC")
		(10 "In4.Cu" signal "L5VCC")
		(12 "In5.Cu" signal "L6")
		(14 "In6.Cu" signal "L7GND")
		(2 "B.Cu" signal "BOTTOM")
		(9 "F.Adhes" user "F.Adhesive")
		(11 "B.Adhes" user "B.Adhesive")
		(13 "F.Paste" user "Package Geometry/Pastemask Top")
		(15 "B.Paste" user "Package Geometry/Pastemask Bottom")
		(5 "F.SilkS" user "Ref Des/Silkscreen Top")
		(7 "B.SilkS" user "Ref Des/Silkscreen Bottom")
		(1 "F.Mask" user "Board Geometry/Soldermask Top")
		(3 "B.Mask" user "Board Geometry/Soldermask Bottom")
		(17 "Dwgs.User" user "User.Drawings")
		(19 "Cmts.User" user "User.Comments")
		(21 "Eco1.User" user "User.Eco1")
		(23 "Eco2.User" user "User.Eco2")
		(25 "Edge.Cuts" user "Board Geometry/Outline")
		(27 "Margin" user)
		(31 "F.CrtYd" user "Package Geometry/Place Bound Top")
		(29 "B.CrtYd" user "Package Geometry/Place Bound Bottom")
		(35 "F.Fab" user "Ref Des/Assembly Top")
		(33 "B.Fab" user "Ref Des/Assembly Bottom")
	)
	(footprint ""
		(layer "F.Cu")
		(at 8.1026 -67.5132 90)
		(property "Reference" "Q14"
			(at 0 0 90)
			(layer "F.SilkS")
			(hide yes)
			(effects
				(font
					(size 1.27 1.27)
				)
			)
		)
		(property "Value" "2N7002K-1-GP"
			(at 0.127 -8.9662 90)
			(unlocked yes)
			(layer "F.Fab")
			(hide yes)
			(effects
				(font
					(size 1.016 1.016)
					(thickness 0.1524)
				)
			)
		)
		(property "Device Type" "SOT23DGS2D4H44"
			(at 0.127 -10.4902 90)
			(unlocked yes)
			(layer "F.Fab")
			(hide yes)
			(effects
				(font
					(size 1.016 1.016)
					(thickness 0.1524)
				)
			)
		)
		(duplicate_pad_numbers_are_jumpers no)
		(fp_line
			(start 1.651 -1.778)
			(end -1.651 -1.778)
			(stroke
				(width 0.1524)
				(type default)
			)
			(layer "F.SilkS")
		)
		(fp_line
			(start -1.651 -1.778)
			(end -1.651 1.778)
			(stroke
				(width 0.1524)
				(type default)
			)
			(layer "F.SilkS")
		)
		(fp_line
			(start 1.651 1.778)
			(end 1.651 -1.778)
			(stroke
				(width 0.1524)
				(type default)
			)
			(layer "F.SilkS")
		)
		(fp_line
			(start -1.651 1.778)
			(end 1.651 1.778)
			(stroke
				(width 0.1524)
				(type default)
			)
			(layer "F.SilkS")
		)
		(fp_poly
			(pts
				(xy -1.778 1.8796) (xy -1.778 -1.8796) (xy 1.778 -1.8796) (xy 1.778 1.8796)
			)
			(stroke
				(width 0)
				(type default)
			)
			(fill no)
			(layer "F.CrtYd")
		)
		(fp_poly
			(pts
				(xy -1.778 1.8796) (xy -1.778 -1.8796) (xy 1.778 -1.8796) (xy 1.778 1.8796)
			)
			(stroke
				(width 0)
				(type default)
			)
			(fill no)
			(layer "F.Fab")
		)
		(pad "D" smd custom
			(at 0 -0.9525 90)
			(size 0.1905 0.1905)
			(layers "F.Cu" "F.Mask" "F.Paste")
			(net "MB0_HS_ENABLE_R")
			(options
				(clearance outline)
				(anchor circle)
			)
			(primitives
				(gr_poly
					(pts
						(arc
							(start -0.1778 0.5715)
							(mid -0.321484 0.511984)
							(end -0.381 0.3683)
						)
						(arc
							(start -0.381 -0.3683)
							(mid -0.321484 -0.511984)
							(end -0.1778 -0.5715)
						)
						(arc
							(start 0.1778 -0.5715)
							(mid 0.321484 -0.511984)
							(end 0.381 -0.3683)
						)
						(arc
							(start 0.381 0.3683)
							(mid 0.321484 0.511984)
							(end 0.1778 0.5715)
						)
					)
					(width 0)
					(fill yes)
				)
			)
		)
		(pad "G" smd custom
			(at -0.98425 0.9525 90)
			(size 0.1905 0.1905)
			(layers "F.Cu" "F.Mask" "F.Paste")
			(net "SCC_HSC_N")
			(options
				(clearance outline)
				(anchor circle)
			)
			(primitives
				(gr_poly
					(pts
						(arc
							(start -0.1778 0.5715)
							(mid -0.321484 0.511984)
							(end -0.381 0.3683)
						)
						(arc
							(start -0.381 -0.3683)
							(mid -0.321484 -0.511984)
							(end -0.1778 -0.5715)
						)
						(arc
							(start 0.1778 -0.5715)
							(mid 0.321484 -0.511984)
							(end 0.381 -0.3683)
						)
						(arc
							(start 0.381 0.3683)
							(mid 0.321484 0.511984)
							(end 0.1778 0.5715)
						)
					)
					(width 0)
					(fill yes)
				)
			)
		)
		(pad "S" smd custom
			(at 0.98425 0.9525 90)
			(size 0.1905 0.1905)
			(layers "F.Cu" "F.Mask" "F.Paste")
			(net "GND")
			(options
				(clearance outline)
				(anchor circle)
			)
			(primitives
				(gr_poly
					(pts
						(arc
							(start -0.1778 0.5715)
							(mid -0.321484 0.511984)
							(end -0.381 0.3683)
						)
						(arc
							(start -0.381 -0.3683)
							(mid -0.321484 -0.511984)
							(end -0.1778 -0.5715)
						)
						(arc
							(start 0.1778 -0.5715)
							(mid 0.321484 -0.511984)
							(end 0.381 -0.3683)
						)
						(arc
							(start 0.381 0.3683)
							(mid 0.321484 0.511984)
							(end 0.1778 0.5715)
						)
					)
					(width 0)
					(fill yes)
				)
			)
		)
	)
	(footprint ""
		(layer "F.Cu")
		(at 13.9192 -38.608 -90)
		(property "Reference" "R531"
			(at 0 0 270)
			(layer "F.SilkS")
			(hide yes)
			(effects
				(font
					(size 1.27 1.27)
				)
			)
		)
		(property "Value" "1KR2J-1-GP"
			(at 0.064008 -3.993896 270)
			(unlocked yes)
			(layer "F.Fab")
			(hide yes)
			(effects
				(font
					(size 1.016 1.016)
					(thickness 0.1524)
				)
			)
		)
		(property "Device Type" "R402H16"
			(at 0.064008 -5.517896 270)
			(unlocked yes)
			(layer "F.Fab")
			(hide yes)
			(effects
				(font
					(size 1.016 1.016)
					(thickness 0.1524)
				)
			)
		)
		(duplicate_pad_numbers_are_jumpers no)
		(fp_line
			(start -0.508 -0.9398)
			(end -0.508 0.9398)
			(stroke
				(width 0.1524)
				(type default)
			)
			(layer "F.SilkS")
		)
		(fp_line
			(start 0.508 -0.9398)
			(end -0.508 -0.9398)
			(stroke
				(width 0.1524)
				(type default)
			)
			(layer "F.SilkS")
		)
		(fp_rect
			(start -0.508 0.9398)
			(end 0.508 -0.9398)
			(stroke
				(width 0)
				(type default)
			)
			(fill no)
			(layer "F.CrtYd")
		)
		(fp_rect
			(start -0.508 0.9398)
			(end 0.508 -0.9398)
			(stroke
				(width 0)
				(type default)
			)
			(fill no)
			(layer "F.Fab")
		)
		(pad "1" smd custom
			(at 0 -0.4445 270)
			(size 0.1397 0.1397)
			(layers "F.Cu" "F.Mask" "F.Paste")
			(net "MB0_CM_VOUT_R")
			(options
				(clearance outline)
				(anchor circle)
			)
			(primitives
				(gr_poly
					(pts
						(arc
							(start -0.1778 -0.2794)
							(mid -0.249642 -0.249642)
							(end -0.2794 -0.1778)
						)
						(arc
							(start -0.2794 0.1778)
							(mid -0.249642 0.249642)
							(end -0.1778 0.2794)
						)
						(arc
							(start 0.1778 0.2794)
							(mid 0.249642 0.249642)
							(end 0.2794 0.1778)
						)
						(arc
							(start 0.2794 -0.1778)
							(mid 0.249642 -0.249642)
							(end 0.1778 -0.2794)
						)
					)
					(width 0)
					(fill yes)
				)
			)
		)
		(pad "2" smd custom
			(at 0 0.4445 270)
			(size 0.1397 0.1397)
			(layers "F.Cu" "F.Mask" "F.Paste")
			(net "P12V_STBY_SCC")
			(options
				(clearance outline)
				(anchor circle)
			)
			(primitives
				(gr_poly
					(pts
						(arc
							(start -0.1778 -0.2794)
							(mid -0.249642 -0.249642)
							(end -0.2794 -0.1778)
						)
						(arc
							(start -0.2794 0.1778)
							(mid -0.249642 0.249642)
							(end -0.1778 0.2794)
						)
						(arc
							(start 0.1778 0.2794)
							(mid 0.249642 0.249642)
							(end 0.2794 0.1778)
						)
						(arc
							(start 0.2794 -0.1778)
							(mid 0.249642 -0.249642)
							(end 0.1778 -0.2794)
						)
					)
					(width 0)
					(fill yes)
				)
			)
		)
	)
	(footprint ""
		(layer "F.Cu")
		(at 131.15798 -44.717716 180)
		(property "Reference" "C44"
			(at 0 0 180)
			(layer "F.SilkS")
			(hide yes)
			(effects
				(font
					(size 1.27 1.27)
				)
			)
		)
		(property "Value" "SCD01U16V1KX-GP"
			(at -2.8321 -1.7399 180)
			(unlocked yes)
			(layer "F.Fab")
			(hide yes)
			(effects
				(font
					(size 1.016 1.016)
					(thickness 0.1524)
				)
			)
		)
		(property "Device Type" "C0201H13"
			(at -2.8321 -3.2639 180)
			(unlocked yes)
			(layer "F.Fab")
			(hide yes)
			(effects
				(font
					(size 1.016 1.016)
					(thickness 0.1524)
				)
			)
		)
		(duplicate_pad_numbers_are_jumpers no)
		(fp_rect
			(start -0.2794 0.6477)
			(end 0.2794 -0.6477)
			(stroke
				(width 0)
				(type default)
			)
			(fill no)
			(layer "F.CrtYd")
		)
		(fp_rect
			(start -0.2794 0.6477)
			(end 0.2794 -0.6477)
			(stroke
				(width 0)
				(type default)
			)
			(fill no)
			(layer "F.Fab")
		)
		(pad "1" smd custom
			(at 0 -0.2794 180)
			(size 0.0762 0.0762)
			(layers "F.Cu" "F.Mask" "F.Paste")
			(net "PHY_IOC_TO_SCC_42_DN")
			(options
				(clearance outline)
				(anchor circle)
			)
			(primitives
				(gr_poly
					(pts
						(arc
							(start 0.1524 -0.127)
							(mid 0.137521 -0.162921)
							(end 0.1016 -0.1778)
						)
						(arc
							(start -0.1016 -0.1778)
							(mid -0.137521 -0.162921)
							(end -0.1524 -0.127)
						)
						(arc
							(start -0.1524 0.127)
							(mid -0.137521 0.162921)
							(end -0.1016 0.1778)
						)
						(arc
							(start 0.1016 0.1778)
							(mid 0.137521 0.162921)
							(end 0.1524 0.127)
						)
					)
					(width 0)
					(fill yes)
				)
			)
		)
		(pad "2" smd custom
			(at 0 0.2794 180)
			(size 0.0762 0.0762)
			(layers "F.Cu" "F.Mask" "F.Paste")
			(net "PHY_IOC_TO_SCC_C_42_DN")
			(options
				(clearance outline)
				(anchor circle)
			)
			(primitives
				(gr_poly
					(pts
						(arc
							(start 0.1524 -0.127)
							(mid 0.137521 -0.162921)
							(end 0.1016 -0.1778)
						)
						(arc
							(start -0.1016 -0.1778)
							(mid -0.137521 -0.162921)
							(end -0.1524 -0.127)
						)
						(arc
							(start -0.1524 0.127)
							(mid -0.137521 0.162921)
							(end -0.1016 0.1778)
						)
						(arc
							(start 0.1016 0.1778)
							(mid 0.137521 0.162921)
							(end 0.1524 0.127)
						)
					)
					(width 0)
					(fill yes)
				)
			)
		)
	)
	(footprint ""
		(layer "F.Cu")
		(at 190.6016 -33.2867)
		(property "Reference" "TP148"
			(at 0 0 0)
			(layer "F.SilkS")
			(hide yes)
			(effects
				(font
					(size 1.27 1.27)
				)
			)
		)
		(property "Value" "TPAD28-2-GP"
			(at -0.0127 -1.6637 0)
			(unlocked yes)
			(layer "F.Fab")
			(hide yes)
			(effects
				(font
					(size 1.016 1.016)
					(thickness 0.1524)
				)
			)
		)
		(property "Device Type" "TPAD28"
			(at -0.0127 -3.1877 0)
			(unlocked yes)
			(layer "F.Fab")
			(hide yes)
			(effects
				(font
					(size 1.016 1.016)
					(thickness 0.1524)
				)
			)
		)
		(duplicate_pad_numbers_are_jumpers no)
		(fp_poly
			(pts
				(arc
					(start 0.3556 0)
					(mid -0.3556 0)
					(end 0.3556 0)
				)
			)
			(stroke
				(width 0)
				(type default)
			)
			(fill no)
			(layer "F.CrtYd")
		)
		(fp_poly
			(pts
				(arc
					(start 0.6096 0)
					(mid -0.6096 0)
					(end 0.6096 0)
				)
			)
			(stroke
				(width 0)
				(type default)
			)
			(fill no)
			(layer "F.Fab")
		)
		(pad "1" smd circle
			(at 0 0)
			(size 0.7112 0.7112)
			(layers "F.Cu" "F.Mask" "F.Paste")
			(net "SPARE4")
		)
	)
	(footprint ""
		(layer "F.Cu")
		(at 185.138822 -90.409268 90)
		(property "Reference" "TC6"
			(at 0 0 90)
			(layer "F.SilkS")
			(hide yes)
			(effects
				(font
					(size 1.27 1.27)
				)
			)
		)
		(property "Value" "SE470UF2VDM-GP"
			(at 0 -9.6012 90)
			(unlocked yes)
			(layer "F.Fab")
			(hide yes)
			(effects
				(font
					(size 1.016 1.016)
					(thickness 0.1524)
				)
			)
		)
		(property "Device Type" "CT7343H83"
			(at 0 -11.1252 90)
			(unlocked yes)
			(layer "F.Fab")
			(hide yes)
			(effects
				(font
					(size 1.016 1.016)
					(thickness 0.1524)
				)
			)
		)
		(duplicate_pad_numbers_are_jumpers no)
		(fp_line
			(start 2.286 -4.8768)
			(end -2.286 -4.8768)
			(stroke
				(width 0.1524)
				(type default)
			)
			(layer "F.SilkS")
		)
		(fp_line
			(start -2.286 -4.8768)
			(end -2.286 -2.032)
			(stroke
				(width 0.1524)
				(type default)
			)
			(layer "F.SilkS")
		)
		(fp_line
			(start 2.1082 -4.699)
			(end -2.1082 -4.699)
			(stroke
				(width 0.508)
				(type default)
			)
			(layer "F.SilkS")
		)
		(fp_line
			(start 2.286 -2.032)
			(end 2.286 -4.8768)
			(stroke
				(width 0.1524)
				(type default)
			)
			(layer "F.SilkS")
		)
		(fp_line
			(start 2.286 2.032)
			(end 2.286 4.8768)
			(stroke
				(width 0.1524)
				(type default)
			)
			(layer "F.SilkS")
		)
		(fp_line
			(start 2.286 4.8768)
			(end -2.286 4.8768)
			(stroke
				(width 0.1524)
				(type default)
			)
			(layer "F.SilkS")
		)
		(fp_line
			(start -2.286 4.8768)
			(end -2.286 2.032)
			(stroke
				(width 0.1524)
				(type default)
			)
			(layer "F.SilkS")
		)
		(fp_rect
			(start -2.1463 3.6449)
			(end 2.1463 -3.6449)
			(stroke
				(width 0)
				(type default)
			)
			(fill no)
			(layer "F.CrtYd")
		)
		(fp_poly
			(pts
				(xy -2.54 4.953) (xy -2.54 4.2926) (xy -3.81 4.2926) (xy -3.81 -4.2926) (xy -2.54 -4.2926) (xy -2.54 -4.953)
				(xy 2.54 -4.953) (xy 2.54 -4.2926) (xy 3.81 -4.2926) (xy 3.81 -1.6256) (xy 2.1463 -1.6256) (xy 2.1463 -3.6449)
				(xy -2.1463 -3.6449) (xy -2.1463 3.6449) (xy 2.1463 3.6449) (xy 2.1463 -1.6129) (xy 3.81 -1.6129)
				(xy 3.81 4.2926) (xy 2.54 4.2926) (xy 2.54 4.953)
			)
			(stroke
				(width 0)
				(type default)
			)
			(fill no)
			(layer "F.CrtYd")
		)
		(fp_rect
			(start 2.54 4.2926)
			(end 3.81 -4.2926)
			(stroke
				(width 0)
				(type default)
			)
			(fill no)
			(layer "F.Fab")
		)
		(fp_rect
			(start -3.81 4.2926)
			(end -2.54 -4.2926)
			(stroke
				(width 0)
				(type default)
			)
			(fill no)
			(layer "F.Fab")
		)
		(fp_rect
			(start -2.54 4.953)
			(end 2.54 -4.953)
			(stroke
				(width 0)
				(type default)
			)
			(fill no)
			(layer "F.Fab")
		)
		(pad "1" smd rect
			(at 0 -3.1496 90)
			(size 2.413 2.286)
			(layers "F.Cu" "F.Mask" "F.Paste")
			(net "P0V975")
		)
		(pad "2" smd rect
			(at 0 3.1496 90)
			(size 2.413 2.286)
			(layers "F.Cu" "F.Mask" "F.Paste")
			(net "GND")
		)
		(zone
			(layer "F.Cu")
			(hatch none 0.5)
			(connect_pads
				(clearance 0)
			)
			(min_thickness 0.25)
			(keepout
				(tracks allowed)
				(vias not_allowed)
				(pads allowed)
				(copperpour not_allowed)
				(footprints allowed)
			)
			(placement
				(enabled no)
				(sheetname "")
			)
			(fill
				(thermal_gap 0.5)
				(thermal_bridge_width 0.5)
				(island_removal_mode 0)
			)
			(polygon
				(pts
					(xy 183.449722 -91.920568) (xy 180.541422 -91.920568) (xy 180.541422 -88.897968) (xy 183.437022 -88.897968)
					(xy 183.767222 -88.897968) (xy 183.767222 -91.920568)
				)
			)
		)
		(zone
			(layer "F.Cu")
			(hatch none 0.5)
			(connect_pads
				(clearance 0)
			)
			(min_thickness 0.25)
			(keepout
				(tracks allowed)
				(vias not_allowed)
				(pads allowed)
				(copperpour not_allowed)
				(footprints allowed)
			)
			(placement
				(enabled no)
				(sheetname "")
			)
			(fill
				(thermal_gap 0.5)
				(thermal_bridge_width 0.5)
				(island_removal_mode 0)
			)
			(polygon
				(pts
					(xy 189.736222 -88.897968) (xy 189.736222 -91.920568) (xy 186.840622 -91.920568) (xy 186.510422 -91.920568)
					(xy 186.510422 -88.897968) (xy 186.840622 -88.897968)
				)
			)
		)
	)
	(footprint ""
		(layer "F.Cu")
		(at 142.35176 -62.448186 -90)
		(property "Reference" "C36"
			(at 0 0 270)
			(layer "F.SilkS")
			(hide yes)
			(effects
				(font
					(size 1.27 1.27)
				)
			)
		)
		(property "Value" "SCD01U16V1KX-GP"
			(at -2.8321 -1.7399 270)
			(unlocked yes)
			(layer "F.Fab")
			(hide yes)
			(effects
				(font
					(size 1.016 1.016)
					(thickness 0.1524)
				)
			)
		)
		(property "Device Type" "C0201H13"
			(at -2.8321 -3.2639 270)
			(unlocked yes)
			(layer "F.Fab")
			(hide yes)
			(effects
				(font
					(size 1.016 1.016)
					(thickness 0.1524)
				)
			)
		)
		(duplicate_pad_numbers_are_jumpers no)
		(fp_rect
			(start -0.2794 0.6477)
			(end 0.2794 -0.6477)
			(stroke
				(width 0)
				(type default)
			)
			(fill no)
			(layer "F.CrtYd")
		)
		(fp_rect
			(start -0.2794 0.6477)
			(end 0.2794 -0.6477)
			(stroke
				(width 0)
				(type default)
			)
			(fill no)
			(layer "F.Fab")
		)
		(pad "1" smd custom
			(at 0 -0.2794 270)
			(size 0.0762 0.0762)
			(layers "F.Cu" "F.Mask" "F.Paste")
			(net "PHY_IOC_TO_SCC_46_DN")
			(options
				(clearance outline)
				(anchor circle)
			)
			(primitives
				(gr_poly
					(pts
						(arc
							(start 0.1524 -0.127)
							(mid 0.137521 -0.162921)
							(end 0.1016 -0.1778)
						)
						(arc
							(start -0.1016 -0.1778)
							(mid -0.137521 -0.162921)
							(end -0.1524 -0.127)
						)
						(arc
							(start -0.1524 0.127)
							(mid -0.137521 0.162921)
							(end -0.1016 0.1778)
						)
						(arc
							(start 0.1016 0.1778)
							(mid 0.137521 0.162921)
							(end 0.1524 0.127)
						)
					)
					(width 0)
					(fill yes)
				)
			)
		)
		(pad "2" smd custom
			(at 0 0.2794 270)
			(size 0.0762 0.0762)
			(layers "F.Cu" "F.Mask" "F.Paste")
			(net "PHY_IOC_TO_SCC_C_46_DN")
			(options
				(clearance outline)
				(anchor circle)
			)
			(primitives
				(gr_poly
					(pts
						(arc
							(start 0.1524 -0.127)
							(mid 0.137521 -0.162921)
							(end 0.1016 -0.1778)
						)
						(arc
							(start -0.1016 -0.1778)
							(mid -0.137521 -0.162921)
							(end -0.1524 -0.127)
						)
						(arc
							(start -0.1524 0.127)
							(mid -0.137521 0.162921)
							(end -0.1016 0.1778)
						)
						(arc
							(start 0.1016 0.1778)
							(mid 0.137521 0.162921)
							(end 0.1524 0.127)
						)
					)
					(width 0)
					(fill yes)
				)
			)
		)
	)
	(footprint ""
		(layer "F.Cu")
		(at 131.57708 -87.282528)
		(property "Reference" "TP35"
			(at 0 0 0)
			(layer "F.SilkS")
			(hide yes)
			(effects
				(font
					(size 1.27 1.27)
				)
			)
		)
		(property "Value" "TPAD28-2-GP"
			(at -0.0127 -1.6637 0)
			(unlocked yes)
			(layer "F.Fab")
			(hide yes)
			(effects
				(font
					(size 1.016 1.016)
					(thickness 0.1524)
				)
			)
		)
		(property "Device Type" "TPAD28"
			(at -0.0127 -3.1877 0)
			(unlocked yes)
			(layer "F.Fab")
			(hide yes)
			(effects
				(font
					(size 1.016 1.016)
					(thickness 0.1524)
				)
			)
		)
		(duplicate_pad_numbers_are_jumpers no)
		(fp_poly
			(pts
				(arc
					(start 0.3556 0)
					(mid -0.3556 0)
					(end 0.3556 0)
				)
			)
			(stroke
				(width 0)
				(type default)
			)
			(fill no)
			(layer "F.CrtYd")
		)
		(fp_poly
			(pts
				(arc
					(start 0.6096 0)
					(mid -0.6096 0)
					(end 0.6096 0)
				)
			)
			(stroke
				(width 0)
				(type default)
			)
			(fill no)
			(layer "F.Fab")
		)
		(pad "1" smd circle
			(at 0 0)
			(size 0.7112 0.7112)
			(layers "F.Cu" "F.Mask" "F.Paste")
			(net "UART_CTS")
		)
	)
)
